# BASEBOARD_FAB2 (Tioga Pass) — schematic netlist excerpt (pin names and nets, part order shuffled) for the footprints in the layout excerpt that follows; sources: Cadence DE-HDL packaged netlist, KiCad conversion of Wiwynn_Tioga_Pass_MB.brd

R25W35  120R2F-GP  1%  pkg RCL_GP  page 151 : \1\ = BMC_M_BA0 ; \2\ = P1V2_AUX_BMC

T1P17  TPAD-DIFF-4P-GP  pkg DISCRET-GB3  page 256
  \1\  = L12_95OHM_6INCH_DP
  \2\  = L12_95OHM_6INCH_DN
  GND1  = GND
  GND2  = GND

(kicad_pcb
	(version 20260206)
	(generator "pcbnew")
	(generator_version "10.0")
	(general
		(thickness 1.6)
		(legacy_teardrops no)
	)
	(paper "A4")
	(title_block
		(title "Wiwynn_Tioga_Pass_MB.brd")
		(comment 1 "Tioga Pass / footprints 1081-1082 of 4770")
	)
	(layers
		(0 "F.Cu" signal "TOP")
		(4 "In1.Cu" signal "L2GND")
		(6 "In2.Cu" signal "L3")
		(8 "In3.Cu" signal "L4GND")
		(10 "In4.Cu" signal "L5")
		(12 "In5.Cu" signal "L6GND")
		(14 "In6.Cu" signal "L7VCC")
		(16 "In7.Cu" signal "L8VCC")
		(18 "In8.Cu" signal "L9GND")
		(20 "In9.Cu" signal "L10")
		(22 "In10.Cu" signal "L11GND")
		(24 "In11.Cu" signal "L12")
		(26 "In12.Cu" signal "L13GND")
		(2 "B.Cu" signal "BOTTOM")
		(9 "F.Adhes" user "F.Adhesive")
		(11 "B.Adhes" user "B.Adhesive")
		(13 "F.Paste" user "Package Geometry/Pastemask Top")
		(15 "B.Paste" user "Package Geometry/Pastemask Bottom")
		(5 "F.SilkS" user "Ref Des/Silkscreen Top")
		(7 "B.SilkS" user "Ref Des/Silkscreen Bottom")
		(1 "F.Mask" user "Board Geometry/Soldermask Top")
		(3 "B.Mask" user "Board Geometry/Soldermask Bottom")
		(17 "Dwgs.User" user "User.Drawings")
		(19 "Cmts.User" user "User.Comments")
		(21 "Eco1.User" user "User.Eco1")
		(23 "Eco2.User" user "User.Eco2")
		(25 "Edge.Cuts" user "Board Geometry/Outline")
		(27 "Margin" user)
		(31 "F.CrtYd" user "Package Geometry/Place Bound Top")
		(29 "B.CrtYd" user "Package Geometry/Place Bound Bottom")
		(35 "F.Fab" user "Ref Des/Assembly Top")
		(33 "B.Fab" user "Ref Des/Assembly Bottom")
	)
	(footprint ""
		(layer "F.Cu")
		(at 292.248082 12.01039 -90)
		(property "Reference" "T1P17"
			(at 0 0 270)
			(layer "F.SilkS")
			(hide yes)
			(effects
				(font
					(size 1.27 1.27)
				)
			)
		)
		(property "Value" "*"
			(at -3.302 1.12395 270)
			(unlocked yes)
			(layer "F.Fab")
			(hide yes)
			(effects
				(font
					(size 0.889 0.889)
					(thickness 0.1524)
				)
			)
		)
		(property "Device Type" "TPAD-DIFF-4P-GP_DISCRET-GB3-TPA"
			(at -3.302 -0.40005 270)
			(unlocked yes)
			(layer "F.Fab")
			(hide yes)
			(effects
				(font
					(size 0.889 0.889)
					(thickness 0.1524)
				)
			)
		)
		(duplicate_pad_numbers_are_jumpers no)
		(fp_line
			(start -2.286 2.286)
			(end 2.286 2.286)
			(stroke
				(width 0.1524)
				(type default)
			)
			(layer "F.SilkS")
		)
		(fp_line
			(start 2.286 2.286)
			(end 2.286 -2.286)
			(stroke
				(width 0.1524)
				(type default)
			)
			(layer "F.SilkS")
		)
		(fp_line
			(start -2.286 -2.286)
			(end -2.286 2.286)
			(stroke
				(width 0.1524)
				(type default)
			)
			(layer "F.SilkS")
		)
		(fp_line
			(start 2.286 -2.286)
			(end -2.286 -2.286)
			(stroke
				(width 0.1524)
				(type default)
			)
			(layer "F.SilkS")
		)
		(fp_line
			(start -2.413 -2.413)
			(end -2.413 -1.143)
			(stroke
				(width 0.4064)
				(type default)
			)
			(layer "F.SilkS")
		)
		(fp_line
			(start -1.143 -2.413)
			(end -2.413 -2.413)
			(stroke
				(width 0.4064)
				(type default)
			)
			(layer "F.SilkS")
		)
		(fp_rect
			(start -2.54 2.54)
			(end 2.54 -2.54)
			(stroke
				(width 0)
				(type default)
			)
			(fill no)
			(layer "F.CrtYd")
		)
		(fp_rect
			(start -2.54 2.54)
			(end 2.54 -2.54)
			(stroke
				(width 0)
				(type default)
			)
			(fill no)
			(layer "F.Fab")
		)
		(pad "1" thru_hole circle
			(at -1.27 -1.27 270)
			(size 1.524 1.524)
			(drill 0.9144)
			(layers "*.Cu" "*.Mask")
			(remove_unused_layers no)
			(net "L12_95OHM_6INCH_DP")
			(clearance -0.0508)
			(thermal_gap 0.127)
			(padstack
				(mode front_inner_back)
				(layer "Inner"
					(shape circle)
					(size 1.1684 1.1684)
					(clearance 0.127)
				)
				(layer "B.Cu"
					(shape circle)
					(size 1.524 1.524)
					(clearance -0.0508)
				)
			)
		)
		(pad "2" thru_hole circle
			(at 1.27 -1.27 270)
			(size 1.524 1.524)
			(drill 0.9144)
			(layers "*.Cu" "*.Mask")
			(remove_unused_layers no)
			(net "L12_95OHM_6INCH_DN")
			(clearance -0.0508)
			(thermal_gap 0.127)
			(padstack
				(mode front_inner_back)
				(layer "Inner"
					(shape circle)
					(size 1.1684 1.1684)
					(clearance 0.127)
				)
				(layer "B.Cu"
					(shape circle)
					(size 1.524 1.524)
					(clearance -0.0508)
				)
			)
		)
		(pad "GND1" thru_hole rect
			(at -1.27 1.27 270)
			(size 1.524 1.524)
			(drill 0.9144)
			(layers "*.Cu" "*.Mask")
			(remove_unused_layers no)
			(net "GND")
			(clearance -0.0508)
			(thermal_gap 0.127)
			(padstack
				(mode front_inner_back)
				(layer "Inner"
					(shape circle)
					(size 1.1684 1.1684)
					(clearance 0.127)
				)
				(layer "B.Cu"
					(shape rect)
					(size 1.524 1.524)
					(clearance -0.0508)
				)
			)
		)
		(pad "GND2" thru_hole rect
			(at 1.27 1.27 270)
			(size 1.524 1.524)
			(drill 0.9144)
			(layers "*.Cu" "*.Mask")
			(remove_unused_layers no)
			(net "GND")
			(clearance -0.0508)
			(thermal_gap 0.127)
			(padstack
				(mode front_inner_back)
				(layer "Inner"
					(shape circle)
					(size 1.1684 1.1684)
					(clearance 0.127)
				)
				(layer "B.Cu"
					(shape rect)
					(size 1.524 1.524)
					(clearance -0.0508)
				)
			)
		)
	)
	(footprint ""
		(layer "F.Cu")
		(at 451.85838 -34.7345 90)
		(property "Reference" "R25W35"
			(at 0 0 90)
			(layer "F.SilkS")
			(hide yes)
			(effects
				(font
					(size 1.27 1.27)
				)
			)
		)
		(property "Value" "*"
			(at 0.064008 -4.108196 90)
			(unlocked yes)
			(layer "F.Fab")
			(hide yes)
			(effects
				(font
					(size 1.27 1.016)
					(thickness 0.1524)
				)
			)
		)
		(property "Device Type" "120R2F-GP_RCL_GP-120R2F-GP,64.A"
			(at 0.064008 -5.632196 90)
			(unlocked yes)
			(layer "F.Fab")
			(hide yes)
			(effects
				(font
					(size 1.27 1.016)
					(thickness 0.1524)
				)
			)
		)
		(duplicate_pad_numbers_are_jumpers no)
		(fp_line
			(start 0.508 -0.9398)
			(end -0.508 -0.9398)
			(stroke
				(width 0.1524)
				(type default)
			)
			(layer "F.SilkS")
		)
		(fp_line
			(start -0.508 -0.9398)
			(end -0.508 0.9398)
			(stroke
				(width 0.1524)
				(type default)
			)
			(layer "F.SilkS")
		)
		(fp_rect
			(start -0.508 0.9398)
			(end 0.508 -0.9398)
			(stroke
				(width 0)
				(type default)
			)
			(fill no)
			(layer "F.CrtYd")
		)
		(fp_rect
			(start -0.508 0.9398)
			(end 0.508 -0.9398)
			(stroke
				(width 0)
				(type default)
			)
			(fill no)
			(layer "F.Fab")
		)
		(pad "1" smd custom
			(at 0 -0.4445 90)
			(size 0.1397 0.1397)
			(layers "F.Cu" "F.Mask" "F.Paste")
			(net "BMC_M_BA0")
			(options
				(clearance outline)
				(anchor circle)
			)
			(primitives
				(gr_poly
					(pts
						(arc
							(start -0.1778 -0.2794)
							(mid -0.249642 -0.249642)
							(end -0.2794 -0.1778)
						)
						(arc
							(start -0.2794 0.1778)
							(mid -0.249642 0.249642)
							(end -0.1778 0.2794)
						)
						(arc
							(start 0.1778 0.2794)
							(mid 0.249642 0.249642)
							(end 0.2794 0.1778)
						)
						(arc
							(start 0.2794 -0.1778)
							(mid 0.249642 -0.249642)
							(end 0.1778 -0.2794)
						)
					)
					(width 0)
					(fill yes)
				)
			)
		)
		(pad "2" smd custom
			(at 0 0.4445 90)
			(size 0.1397 0.1397)
			(layers "F.Cu" "F.Mask" "F.Paste")
			(net "P1V2_AUX_BMC")
			(options
				(clearance outline)
				(anchor circle)
			)
			(primitives
				(gr_poly
					(pts
						(arc
							(start -0.1778 -0.2794)
							(mid -0.249642 -0.249642)
							(end -0.2794 -0.1778)
						)
						(arc
							(start -0.2794 0.1778)
							(mid -0.249642 0.249642)
							(end -0.1778 0.2794)
						)
						(arc
							(start 0.1778 0.2794)
							(mid 0.249642 0.249642)
							(end 0.2794 0.1778)
						)
						(arc
							(start 0.2794 -0.1778)
							(mid 0.249642 -0.249642)
							(end 0.1778 -0.2794)
						)
					)
					(width 0)
					(fill yes)
				)
			)
		)
	)
)
